(kicad_pcb
	(version 20241229)
	(generator "pcbnew")
	(generator_version "9.0")
	(general
		(thickness 1.599998)
		(legacy_teardrops no)
	)
	(paper "A4")
	(title_block
		(date "2023-02-12")
		(rev "1.1.5")
		(comment 9 "footprints 36-42 of 473")
	)
	(layers
		(0 "F.Cu" signal)
		(4 "In1.Cu" power "In1.GND")
		(6 "In2.Cu" signal)
		(8 "In3.Cu" power "In3.GND")
		(10 "In4.Cu" power "In4.VCC")
		(12 "In5.Cu" signal)
		(14 "In6.Cu" power "In6.VCC")
		(2 "B.Cu" signal)
		(9 "F.Adhes" user "F.Adhesive")
		(11 "B.Adhes" user "B.Adhesive")
		(13 "F.Paste" user)
		(15 "B.Paste" user)
		(5 "F.SilkS" user "F.Silkscreen")
		(7 "B.SilkS" user "B.Silkscreen")
		(1 "F.Mask" user)
		(3 "B.Mask" user)
		(17 "Dwgs.User" user "User.Drawings")
		(19 "Cmts.User" user "User.Comments")
		(21 "Eco1.User" user "User.Eco1")
		(23 "Eco2.User" user "User.Eco2")
		(25 "Edge.Cuts" user)
		(27 "Margin" user)
		(31 "F.CrtYd" user "F.Courtyard")
		(29 "B.CrtYd" user "B.Courtyard")
		(35 "F.Fab" user)
		(33 "B.Fab" user)
	)
	(footprint "antmicro-footprints:R_0402_1005Metric"
		(layer "F.Cu")
		(at 148.036328 104.371157)
		(descr "Resistor SMD 0402")
		(tags "resistor SMD 0402")
		(property "Reference" "R20"
			(at 0.763672 0.428843 0)
			(layer "F.SilkS")
			(effects
				(font
					(size 0.7 0.7)
					(thickness 0.15)
				)
				(justify left bottom)
			)
		)
		(property "Value" "R_22R_0402"
			(at 0 1.4 0)
			(layer "F.Fab")
			(effects
				(font
					(size 0.7 0.7)
					(thickness 0.15)
				)
				(justify left bottom)
			)
		)
		(property "Description" "22R resistor in 0402 package with 1% tolerance"
			(at 0 0 0)
			(layer "F.Fab")
			(hide yes)
			(effects
				(font
					(size 1.27 1.27)
					(thickness 0.15)
				)
			)
		)
		(property "Author" "Antmicro"
			(at 0 0 0)
			(layer "F.Fab")
			(hide yes)
			(effects
				(font
					(size 1 1)
					(thickness 0.15)
				)
			)
		)
		(property "License" "Apache-2.0"
			(at 0 0 0)
			(layer "F.Fab")
			(hide yes)
			(effects
				(font
					(size 1 1)
					(thickness 0.15)
				)
			)
		)
		(property "MPN" "CR0402-FX-22R0GLF"
			(at 0 0 0)
			(layer "F.Fab")
			(hide yes)
			(effects
				(font
					(size 1 1)
					(thickness 0.15)
				)
			)
		)
		(property "Manufacturer" "Bourns"
			(at 0 0 0)
			(layer "F.Fab")
			(hide yes)
			(effects
				(font
					(size 1 1)
					(thickness 0.15)
				)
			)
		)
		(property "Tolerance" "1%"
			(at 0 0 0)
			(layer "F.Fab")
			(hide yes)
			(effects
				(font
					(size 1 1)
					(thickness 0.15)
				)
			)
		)
		(property "Val" "22R"
			(at 0 0 0)
			(layer "F.Fab")
			(hide yes)
			(effects
				(font
					(size 1 1)
					(thickness 0.15)
				)
			)
		)
		(sheetname "Interfaces")
		(sheetfile "interfaces.kicad_sch")
		(attr smd)
		(fp_rect
			(start -0.93 -0.47)
			(end 0.93 0.47)
			(stroke
				(width 0.05)
				(type solid)
			)
			(fill no)
			(layer "F.CrtYd")
		)
		(fp_rect
			(start -0.5 -0.25)
			(end 0.5 0.25)
			(stroke
				(width 0.15)
				(type solid)
			)
			(fill no)
			(layer "F.Fab")
		)
		(pad "1" smd roundrect
			(at -0.485 0)
			(size 0.59 0.64)
			(layers "F.Cu" "F.Mask" "F.Paste")
			(roundrect_rratio 0.25)
			(net 249 "Net-(U4-BDBUS3)")
			(pintype "passive")
		)
		(pad "2" smd roundrect
			(at 0.485 0)
			(size 0.59 0.64)
			(layers "F.Cu" "F.Mask" "F.Paste")
			(roundrect_rratio 0.25)
			(net 447 "AUX_JTAG_TMS")
			(pintype "passive")
		)
	)
	(footprint "antmicro-footprints:R_0402_1005Metric"
		(layer "F.Cu")
		(at 148.056328 109.831157)
		(descr "Resistor SMD 0402")
		(tags "resistor SMD 0402")
		(property "Reference" "R16"
			(at 0.763672 0.428843 0)
			(layer "F.SilkS")
			(effects
				(font
					(size 0.7 0.7)
					(thickness 0.15)
				)
				(justify left bottom)
			)
		)
		(property "Value" "R_22R_0402"
			(at 0 1.4 0)
			(layer "F.Fab")
			(effects
				(font
					(size 0.7 0.7)
					(thickness 0.15)
				)
				(justify left bottom)
			)
		)
		(property "Description" "22R resistor in 0402 package with 1% tolerance"
			(at 0 0 0)
			(layer "F.Fab")
			(hide yes)
			(effects
				(font
					(size 1.27 1.27)
					(thickness 0.15)
				)
			)
		)
		(property "Author" "Antmicro"
			(at 0 0 0)
			(layer "F.Fab")
			(hide yes)
			(effects
				(font
					(size 1 1)
					(thickness 0.15)
				)
			)
		)
		(property "License" "Apache-2.0"
			(at 0 0 0)
			(layer "F.Fab")
			(hide yes)
			(effects
				(font
					(size 1 1)
					(thickness 0.15)
				)
			)
		)
		(property "MPN" "CR0402-FX-22R0GLF"
			(at 0 0 0)
			(layer "F.Fab")
			(hide yes)
			(effects
				(font
					(size 1 1)
					(thickness 0.15)
				)
			)
		)
		(property "Manufacturer" "Bourns"
			(at 0 0 0)
			(layer "F.Fab")
			(hide yes)
			(effects
				(font
					(size 1 1)
					(thickness 0.15)
				)
			)
		)
		(property "Tolerance" "1%"
			(at 0 0 0)
			(layer "F.Fab")
			(hide yes)
			(effects
				(font
					(size 1 1)
					(thickness 0.15)
				)
			)
		)
		(property "Val" "22R"
			(at 0 0 0)
			(layer "F.Fab")
			(hide yes)
			(effects
				(font
					(size 1 1)
					(thickness 0.15)
				)
			)
		)
		(sheetname "Interfaces")
		(sheetfile "interfaces.kicad_sch")
		(attr smd)
		(fp_rect
			(start -0.93 -0.47)
			(end 0.93 0.47)
			(stroke
				(width 0.05)
				(type solid)
			)
			(fill no)
			(layer "F.CrtYd")
		)
		(fp_rect
			(start -0.5 -0.25)
			(end 0.5 0.25)
			(stroke
				(width 0.15)
				(type solid)
			)
			(fill no)
			(layer "F.Fab")
		)
		(pad "1" smd roundrect
			(at -0.485 0)
			(size 0.59 0.64)
			(layers "F.Cu" "F.Mask" "F.Paste")
			(roundrect_rratio 0.25)
			(net 245 "Net-(U4-ADBUS3)")
			(pintype "passive")
		)
		(pad "2" smd roundrect
			(at 0.485 0)
			(size 0.59 0.64)
			(layers "F.Cu" "F.Mask" "F.Paste")
			(roundrect_rratio 0.25)
			(net 9 "TMS_JTAG")
			(pintype "passive")
		)
	)
	(footprint "antmicro-footprints:R_0402_1005Metric"
		(layer "F.Cu")
		(at 148.056328 110.906157)
		(descr "Resistor SMD 0402")
		(tags "resistor SMD 0402")
		(property "Reference" "R15"
			(at 0.763672 0.428843 0)
			(layer "F.SilkS")
			(effects
				(font
					(size 0.7 0.7)
					(thickness 0.15)
				)
				(justify left bottom)
			)
		)
		(property "Value" "R_22R_0402"
			(at 0 1.4 0)
			(layer "F.Fab")
			(effects
				(font
					(size 0.7 0.7)
					(thickness 0.15)
				)
				(justify left bottom)
			)
		)
		(property "Description" "22R resistor in 0402 package with 1% tolerance"
			(at 0 0 0)
			(layer "F.Fab")
			(hide yes)
			(effects
				(font
					(size 1.27 1.27)
					(thickness 0.15)
				)
			)
		)
		(property "Author" "Antmicro"
			(at 0 0 0)
			(layer "F.Fab")
			(hide yes)
			(effects
				(font
					(size 1 1)
					(thickness 0.15)
				)
			)
		)
		(property "License" "Apache-2.0"
			(at 0 0 0)
			(layer "F.Fab")
			(hide yes)
			(effects
				(font
					(size 1 1)
					(thickness 0.15)
				)
			)
		)
		(property "MPN" "CR0402-FX-22R0GLF"
			(at 0 0 0)
			(layer "F.Fab")
			(hide yes)
			(effects
				(font
					(size 1 1)
					(thickness 0.15)
				)
			)
		)
		(property "Manufacturer" "Bourns"
			(at 0 0 0)
			(layer "F.Fab")
			(hide yes)
			(effects
				(font
					(size 1 1)
					(thickness 0.15)
				)
			)
		)
		(property "Tolerance" "1%"
			(at 0 0 0)
			(layer "F.Fab")
			(hide yes)
			(effects
				(font
					(size 1 1)
					(thickness 0.15)
				)
			)
		)
		(property "Val" "22R"
			(at 0 0 0)
			(layer "F.Fab")
			(hide yes)
			(effects
				(font
					(size 1 1)
					(thickness 0.15)
				)
			)
		)
		(sheetname "Interfaces")
		(sheetfile "interfaces.kicad_sch")
		(attr smd)
		(fp_rect
			(start -0.93 -0.47)
			(end 0.93 0.47)
			(stroke
				(width 0.05)
				(type solid)
			)
			(fill no)
			(layer "F.CrtYd")
		)
		(fp_rect
			(start -0.5 -0.25)
			(end 0.5 0.25)
			(stroke
				(width 0.15)
				(type solid)
			)
			(fill no)
			(layer "F.Fab")
		)
		(pad "1" smd roundrect
			(at -0.485 0)
			(size 0.59 0.64)
			(layers "F.Cu" "F.Mask" "F.Paste")
			(roundrect_rratio 0.25)
			(net 243 "Net-(U4-ADBUS2)")
			(pintype "passive")
		)
		(pad "2" smd roundrect
			(at 0.485 0)
			(size 0.59 0.64)
			(layers "F.Cu" "F.Mask" "F.Paste")
			(roundrect_rratio 0.25)
			(net 11 "TDO_JTAG")
			(pintype "passive")
		)
	)
	(footprint "antmicro-footprints:R_0402_1005Metric"
		(layer "F.Cu")
		(at 148.056328 111.981157)
		(descr "Resistor SMD 0402")
		(tags "resistor SMD 0402")
		(property "Reference" "R14"
			(at 0.763672 0.428843 0)
			(layer "F.SilkS")
			(effects
				(font
					(size 0.7 0.7)
					(thickness 0.15)
				)
				(justify left bottom)
			)
		)
		(property "Value" "R_22R_0402"
			(at 0 1.4 0)
			(layer "F.Fab")
			(effects
				(font
					(size 0.7 0.7)
					(thickness 0.15)
				)
				(justify left bottom)
			)
		)
		(property "Description" "22R resistor in 0402 package with 1% tolerance"
			(at 0 0 0)
			(layer "F.Fab")
			(hide yes)
			(effects
				(font
					(size 1.27 1.27)
					(thickness 0.15)
				)
			)
		)
		(property "Author" "Antmicro"
			(at 0 0 0)
			(layer "F.Fab")
			(hide yes)
			(effects
				(font
					(size 1 1)
					(thickness 0.15)
				)
			)
		)
		(property "License" "Apache-2.0"
			(at 0 0 0)
			(layer "F.Fab")
			(hide yes)
			(effects
				(font
					(size 1 1)
					(thickness 0.15)
				)
			)
		)
		(property "MPN" "CR0402-FX-22R0GLF"
			(at 0 0 0)
			(layer "F.Fab")
			(hide yes)
			(effects
				(font
					(size 1 1)
					(thickness 0.15)
				)
			)
		)
		(property "Manufacturer" "Bourns"
			(at 0 0 0)
			(layer "F.Fab")
			(hide yes)
			(effects
				(font
					(size 1 1)
					(thickness 0.15)
				)
			)
		)
		(property "Tolerance" "1%"
			(at 0 0 0)
			(layer "F.Fab")
			(hide yes)
			(effects
				(font
					(size 1 1)
					(thickness 0.15)
				)
			)
		)
		(property "Val" "22R"
			(at 0 0 0)
			(layer "F.Fab")
			(hide yes)
			(effects
				(font
					(size 1 1)
					(thickness 0.15)
				)
			)
		)
		(sheetname "Interfaces")
		(sheetfile "interfaces.kicad_sch")
		(attr smd)
		(fp_rect
			(start -0.93 -0.47)
			(end 0.93 0.47)
			(stroke
				(width 0.05)
				(type solid)
			)
			(fill no)
			(layer "F.CrtYd")
		)
		(fp_rect
			(start -0.5 -0.25)
			(end 0.5 0.25)
			(stroke
				(width 0.15)
				(type solid)
			)
			(fill no)
			(layer "F.Fab")
		)
		(pad "1" smd roundrect
			(at -0.485 0)
			(size 0.59 0.64)
			(layers "F.Cu" "F.Mask" "F.Paste")
			(roundrect_rratio 0.25)
			(net 242 "Net-(U4-ADBUS1)")
			(pintype "passive")
		)
		(pad "2" smd roundrect
			(at 0.485 0)
			(size 0.59 0.64)
			(layers "F.Cu" "F.Mask" "F.Paste")
			(roundrect_rratio 0.25)
			(net 10 "TDI_JTAG")
			(pintype "passive")
		)
	)
	(footprint "antmicro-footprints:R_0402_1005Metric"
		(layer "F.Cu")
		(at 148.036328 113.121157)
		(descr "Resistor SMD 0402")
		(tags "resistor SMD 0402")
		(property "Reference" "R13"
			(at 0.763672 0.428843 0)
			(layer "F.SilkS")
			(effects
				(font
					(size 0.7 0.7)
					(thickness 0.15)
				)
				(justify left bottom)
			)
		)
		(property "Value" "R_22R_0402"
			(at 0 1.4 0)
			(layer "F.Fab")
			(effects
				(font
					(size 0.7 0.7)
					(thickness 0.15)
				)
				(justify left bottom)
			)
		)
		(property "Description" "22R resistor in 0402 package with 1% tolerance"
			(at 0 0 0)
			(layer "F.Fab")
			(hide yes)
			(effects
				(font
					(size 1.27 1.27)
					(thickness 0.15)
				)
			)
		)
		(property "Author" "Antmicro"
			(at 0 0 0)
			(layer "F.Fab")
			(hide yes)
			(effects
				(font
					(size 1 1)
					(thickness 0.15)
				)
			)
		)
		(property "License" "Apache-2.0"
			(at 0 0 0)
			(layer "F.Fab")
			(hide yes)
			(effects
				(font
					(size 1 1)
					(thickness 0.15)
				)
			)
		)
		(property "MPN" "CR0402-FX-22R0GLF"
			(at 0 0 0)
			(layer "F.Fab")
			(hide yes)
			(effects
				(font
					(size 1 1)
					(thickness 0.15)
				)
			)
		)
		(property "Manufacturer" "Bourns"
			(at 0 0 0)
			(layer "F.Fab")
			(hide yes)
			(effects
				(font
					(size 1 1)
					(thickness 0.15)
				)
			)
		)
		(property "Tolerance" "1%"
			(at 0 0 0)
			(layer "F.Fab")
			(hide yes)
			(effects
				(font
					(size 1 1)
					(thickness 0.15)
				)
			)
		)
		(property "Val" "22R"
			(at 0 0 0)
			(layer "F.Fab")
			(hide yes)
			(effects
				(font
					(size 1 1)
					(thickness 0.15)
				)
			)
		)
		(sheetname "Interfaces")
		(sheetfile "interfaces.kicad_sch")
		(attr smd)
		(fp_rect
			(start -0.93 -0.47)
			(end 0.93 0.47)
			(stroke
				(width 0.05)
				(type solid)
			)
			(fill no)
			(layer "F.CrtYd")
		)
		(fp_rect
			(start -0.5 -0.25)
			(end 0.5 0.25)
			(stroke
				(width 0.15)
				(type solid)
			)
			(fill no)
			(layer "F.Fab")
		)
		(pad "1" smd roundrect
			(at -0.485 0)
			(size 0.59 0.64)
			(layers "F.Cu" "F.Mask" "F.Paste")
			(roundrect_rratio 0.25)
			(net 241 "Net-(U4-ADBUS0)")
			(pintype "passive")
		)
		(pad "2" smd roundrect
			(at 0.485 0)
			(size 0.59 0.64)
			(layers "F.Cu" "F.Mask" "F.Paste")
			(roundrect_rratio 0.25)
			(net 8 "TCK_JTAG")
			(pintype "passive")
		)
	)
	(footprint "antmicro-footprints:C_0402_1005Metric"
		(layer "F.Cu")
		(at 135.1 108.099 180)
		(descr "Capacitor SMD 0402")
		(tags "capacitor SMD 0402")
		(property "Reference" "C9"
			(at 0.8 -1.201 180)
			(layer "F.SilkS")
			(effects
				(font
					(size 0.7 0.7)
					(thickness 0.15)
				)
				(justify left bottom)
			)
		)
		(property "Value" "C_100n_6V3_0402"
			(at 0 1.4 180)
			(layer "F.Fab")
			(effects
				(font
					(size 0.7 0.7)
					(thickness 0.15)
				)
				(justify left bottom)
			)
		)
		(property "Description" " "
			(at 0 0 180)
			(layer "F.Fab")
			(hide yes)
			(effects
				(font
					(size 1.27 1.27)
					(thickness 0.15)
				)
			)
		)
		(property "Author" "Antmicro"
			(at 270.2 216.198 0)
			(layer "F.Fab")
			(hide yes)
			(effects
				(font
					(size 1 1)
					(thickness 0.15)
				)
			)
		)
		(property "Dielectric" ""
			(at 270.2 216.198 0)
			(layer "F.Fab")
			(hide yes)
			(effects
				(font
					(size 1 1)
					(thickness 0.15)
				)
			)
		)
		(property "License" "Apache-2.0"
			(at 270.2 216.198 0)
			(layer "F.Fab")
			(hide yes)
			(effects
				(font
					(size 1 1)
					(thickness 0.15)
				)
			)
		)
		(property "MPN" "0402X104K6R3CT"
			(at 270.2 216.198 0)
			(layer "F.Fab")
			(hide yes)
			(effects
				(font
					(size 1 1)
					(thickness 0.15)
				)
			)
		)
		(property "Manufacturer" "Walsin"
			(at 270.2 216.198 0)
			(layer "F.Fab")
			(hide yes)
			(effects
				(font
					(size 1 1)
					(thickness 0.15)
				)
			)
		)
		(property "Val" "100n"
			(at 270.2 216.198 0)
			(layer "F.Fab")
			(hide yes)
			(effects
				(font
					(size 1 1)
					(thickness 0.15)
				)
			)
		)
		(property "Voltage" ""
			(at 270.2 216.198 0)
			(layer "F.Fab")
			(hide yes)
			(effects
				(font
					(size 1 1)
					(thickness 0.15)
				)
			)
		)
		(sheetname "Interfaces")
		(sheetfile "interfaces.kicad_sch")
		(attr smd)
		(fp_rect
			(start -0.94 -0.47)
			(end 0.94 0.47)
			(stroke
				(width 0.05)
				(type solid)
			)
			(fill no)
			(layer "F.CrtYd")
		)
		(fp_rect
			(start -0.499 -0.249)
			(end 0.499 0.249)
			(stroke
				(width 0.15)
				(type solid)
			)
			(fill no)
			(layer "F.Fab")
		)
		(pad "1" smd roundrect
			(at -0.484 0 180)
			(size 0.59 0.64)
			(layers "F.Cu" "F.Mask" "F.Paste")
			(roundrect_rratio 0.25)
			(net 459 "3V3_SYS")
			(pintype "passive")
		)
		(pad "2" smd roundrect
			(at 0.484 0 180)
			(size 0.59 0.64)
			(layers "F.Cu" "F.Mask" "F.Paste")
			(roundrect_rratio 0.25)
			(net 5 "GND")
			(pintype "passive")
		)
	)
	(footprint "antmicro-footprints:C_0402_1005Metric"
		(layer "F.Cu")
		(at 132.661328 115.996157 90)
		(descr "Capacitor SMD 0402")
		(tags "capacitor SMD 0402")
		(property "Reference" "C16"
			(at 0.796157 0.438672 90)
			(layer "F.SilkS")
			(effects
				(font
					(size 0.7 0.7)
					(thickness 0.15)
				)
				(justify left bottom)
			)
		)
		(property "Value" "C_18p_0402"
			(at 0 1.4 90)
			(layer "F.Fab")
			(effects
				(font
					(size 0.7 0.7)
					(thickness 0.15)
				)
				(justify left bottom)
			)
		)
		(property "Description" " "
			(at 0 0 90)
			(layer "F.Fab")
			(hide yes)
			(effects
				(font
					(size 1.27 1.27)
					(thickness 0.15)
				)
			)
		)
		(property "Author" "Antmicro"
			(at 248.657485 -16.665171 0)
			(layer "F.Fab")
			(hide yes)
			(effects
				(font
					(size 1 1)
					(thickness 0.15)
				)
			)
		)
		(property "Dielectric" ""
			(at 248.657485 -16.665171 0)
			(layer "F.Fab")
			(hide yes)
			(effects
				(font
					(size 1 1)
					(thickness 0.15)
				)
			)
		)
		(property "License" "Apache-2.0"
			(at 248.657485 -16.665171 0)
			(layer "F.Fab")
			(hide yes)
			(effects
				(font
					(size 1 1)
					(thickness 0.15)
				)
			)
		)
		(property "MPN" "MC0402N180J500CT"
			(at 248.657485 -16.665171 0)
			(layer "F.Fab")
			(hide yes)
			(effects
				(font
					(size 1 1)
					(thickness 0.15)
				)
			)
		)
		(property "Manufacturer" "Multicomp"
			(at 248.657485 -16.665171 0)
			(layer "F.Fab")
			(hide yes)
			(effects
				(font
					(size 1 1)
					(thickness 0.15)
				)
			)
		)
		(property "Val" "18p"
			(at 248.657485 -16.665171 0)
			(layer "F.Fab")
			(hide yes)
			(effects
				(font
					(size 1 1)
					(thickness 0.15)
				)
			)
		)
		(property "Voltage" ""
			(at 248.657485 -16.665171 0)
			(layer "F.Fab")
			(hide yes)
			(effects
				(font
					(size 1 1)
					(thickness 0.15)
				)
			)
		)
		(sheetname "Interfaces")
		(sheetfile "interfaces.kicad_sch")
		(attr smd)
		(fp_rect
			(start -0.94 -0.47)
			(end 0.94 0.47)
			(stroke
				(width 0.05)
				(type solid)
			)
			(fill no)
			(layer "F.CrtYd")
		)
		(fp_rect
			(start -0.499 -0.249)
			(end 0.499 0.249)
			(stroke
				(width 0.15)
				(type solid)
			)
			(fill no)
			(layer "F.Fab")
		)
		(pad "1" smd roundrect
			(at -0.484 0 90)
			(size 0.59 0.64)
			(layers "F.Cu" "F.Mask" "F.Paste")
			(roundrect_rratio 0.25)
			(net 5 "GND")
			(pintype "passive")
		)
		(pad "2" smd roundrect
			(at 0.484 0 90)
			(size 0.59 0.64)
			(layers "F.Cu" "F.Mask" "F.Paste")
			(roundrect_rratio 0.25)
			(net 3 "Net-(U4-OSCI)")
			(pintype "passive")
		)
	)
)
